(kicad_pcb
	(version 20260206)
	(generator "pcbnew")
	(generator_version "10.0")
	(general
		(thickness 1.6)
		(legacy_teardrops no)
	)
	(paper "A4")
	(title_block
		(title "04192023_DAF0TMB3IC0_F0TG_MB_C_brd_V02_OCP.brd")
		(comment 1 "Grand Teton / footprints 7018-7024 of 8354")
	)
	(layers
		(0 "F.Cu" signal "TOP")
		(4 "In1.Cu" signal "GND")
		(6 "In2.Cu" signal "IN1")
		(8 "In3.Cu" signal "GND1")
		(10 "In4.Cu" signal "IN2")
		(12 "In5.Cu" signal "GND2")
		(14 "In6.Cu" signal "IN3")
		(16 "In7.Cu" signal "GND3")
		(18 "In8.Cu" signal "VCC")
		(20 "In9.Cu" signal "VCC1")
		(22 "In10.Cu" signal "GND4")
		(24 "In11.Cu" signal "IN4")
		(26 "In12.Cu" signal "GND5")
		(28 "In13.Cu" signal "IN5")
		(30 "In14.Cu" signal "GND6")
		(32 "In15.Cu" signal "IN6")
		(34 "In16.Cu" signal "GND7")
		(2 "B.Cu" signal "BOTTOM")
		(9 "F.Adhes" user "F.Adhesive")
		(11 "B.Adhes" user "B.Adhesive")
		(13 "F.Paste" user "Package Geometry/Pastemask Top")
		(15 "B.Paste" user "Package Geometry/Pastemask Bottom")
		(5 "F.SilkS" user "Ref Des/Silkscreen Top")
		(7 "B.SilkS" user "Ref Des/Silkscreen Bottom")
		(1 "F.Mask" user "Board Geometry/Soldermask Top")
		(3 "B.Mask" user "Board Geometry/Soldermask Bottom")
		(17 "Dwgs.User" user "User.Drawings")
		(19 "Cmts.User" user "User.Comments")
		(21 "Eco1.User" user "User.Eco1")
		(23 "Eco2.User" user "User.Eco2")
		(25 "Edge.Cuts" user "Board Geometry/Outline")
		(27 "Margin" user)
		(31 "F.CrtYd" user "Package Geometry/Place Bound Top")
		(29 "B.CrtYd" user "Package Geometry/Place Bound Bottom")
		(35 "F.Fab" user "Ref Des/Assembly Top")
		(33 "B.Fab" user "Ref Des/Assembly Bottom")
	)
	(footprint ""
		(layer "B.Cu")
		(at 378.504958 -208.530952 -90)
		(property "Reference" "R402"
			(at 0 0 90)
			(layer "B.SilkS")
			(hide yes)
			(effects
				(font
					(size 1.27 1.27)
				)
				(justify mirror)
			)
		)
		(property "Value" ""
			(at 0 0 90)
			(layer "B.Fab")
			(effects
				(font
					(size 1.27 1.27)
				)
				(justify mirror)
			)
		)
		(duplicate_pad_numbers_are_jumpers no)
		(fp_line
			(start -0.7874 0.4064)
			(end 0.7874 0.4064)
			(stroke
				(width 0.1524)
				(type default)
			)
			(layer "B.SilkS")
		)
		(fp_line
			(start 0.7874 0.4064)
			(end 0.7874 -0.4064)
			(stroke
				(width 0.1524)
				(type default)
			)
			(layer "B.SilkS")
		)
		(fp_line
			(start -0.7874 -0.4064)
			(end -0.7874 0.4064)
			(stroke
				(width 0.1524)
				(type default)
			)
			(layer "B.SilkS")
		)
		(fp_line
			(start 0.7874 -0.4064)
			(end -0.7874 -0.4064)
			(stroke
				(width 0.1524)
				(type default)
			)
			(layer "B.SilkS")
		)
		(fp_line
			(start -0.67945 0.3048)
			(end -0.120396 0.3048)
			(stroke
				(width 0.1)
				(type default)
			)
			(layer "B.Fab")
		)
		(fp_line
			(start -0.120396 0.3048)
			(end -0.120396 0.2794)
			(stroke
				(width 0.1)
				(type default)
			)
			(layer "B.Fab")
		)
		(fp_line
			(start 0.12065 0.3048)
			(end 0.67945 0.3048)
			(stroke
				(width 0.1)
				(type default)
			)
			(layer "B.Fab")
		)
		(fp_line
			(start 0.67945 0.3048)
			(end 0.67945 -0.305054)
			(stroke
				(width 0.1)
				(type default)
			)
			(layer "B.Fab")
		)
		(fp_line
			(start -0.120396 0.2794)
			(end 0.12065 0.2794)
			(stroke
				(width 0.1)
				(type default)
			)
			(layer "B.Fab")
		)
		(fp_line
			(start 0.12065 0.2794)
			(end 0.12065 0.3048)
			(stroke
				(width 0.1)
				(type default)
			)
			(layer "B.Fab")
		)
		(fp_line
			(start -0.12065 -0.2794)
			(end -0.12065 -0.3048)
			(stroke
				(width 0.1)
				(type default)
			)
			(layer "B.Fab")
		)
		(fp_line
			(start 0.12065 -0.2794)
			(end -0.12065 -0.2794)
			(stroke
				(width 0.1)
				(type default)
			)
			(layer "B.Fab")
		)
		(fp_line
			(start -0.67945 -0.3048)
			(end -0.67945 0.3048)
			(stroke
				(width 0.1)
				(type default)
			)
			(layer "B.Fab")
		)
		(fp_line
			(start -0.12065 -0.3048)
			(end -0.67945 -0.3048)
			(stroke
				(width 0.1)
				(type default)
			)
			(layer "B.Fab")
		)
		(fp_line
			(start 0.12065 -0.305054)
			(end 0.12065 -0.2794)
			(stroke
				(width 0.1)
				(type default)
			)
			(layer "B.Fab")
		)
		(fp_line
			(start 0.67945 -0.305054)
			(end 0.12065 -0.305054)
			(stroke
				(width 0.1)
				(type default)
			)
			(layer "B.Fab")
		)
		(pad "1" smd circle
			(at 0.40005 0 90)
			(size 0 0)
			(layers "B.Cu" "B.Mask" "B.Paste")
			(net "PVDD18_S5_P0")
		)
		(pad "2" smd circle
			(at -0.40005 0 90)
			(size 0 0)
			(layers "B.Cu" "B.Mask" "B.Paste")
			(net "JTAG_CPU0_TMS")
		)
	)
	(footprint ""
		(layer "B.Cu")
		(at 238.379 -231.648 -90)
		(property "Reference" "R366"
			(at 0 0 90)
			(layer "B.SilkS")
			(hide yes)
			(effects
				(font
					(size 1.27 1.27)
				)
				(justify mirror)
			)
		)
		(property "Value" ""
			(at 0 0 90)
			(layer "B.Fab")
			(effects
				(font
					(size 1.27 1.27)
				)
				(justify mirror)
			)
		)
		(duplicate_pad_numbers_are_jumpers no)
		(fp_line
			(start -0.7874 0.4064)
			(end 0.7874 0.4064)
			(stroke
				(width 0.1524)
				(type default)
			)
			(layer "B.SilkS")
		)
		(fp_line
			(start 0.7874 0.4064)
			(end 0.7874 -0.4064)
			(stroke
				(width 0.1524)
				(type default)
			)
			(layer "B.SilkS")
		)
		(fp_line
			(start -0.7874 -0.4064)
			(end -0.7874 0.4064)
			(stroke
				(width 0.1524)
				(type default)
			)
			(layer "B.SilkS")
		)
		(fp_line
			(start 0.7874 -0.4064)
			(end -0.7874 -0.4064)
			(stroke
				(width 0.1524)
				(type default)
			)
			(layer "B.SilkS")
		)
		(fp_line
			(start -0.67945 0.3048)
			(end -0.120396 0.3048)
			(stroke
				(width 0.1)
				(type default)
			)
			(layer "B.Fab")
		)
		(fp_line
			(start -0.120396 0.3048)
			(end -0.120396 0.2794)
			(stroke
				(width 0.1)
				(type default)
			)
			(layer "B.Fab")
		)
		(fp_line
			(start 0.12065 0.3048)
			(end 0.67945 0.3048)
			(stroke
				(width 0.1)
				(type default)
			)
			(layer "B.Fab")
		)
		(fp_line
			(start 0.67945 0.3048)
			(end 0.67945 -0.305054)
			(stroke
				(width 0.1)
				(type default)
			)
			(layer "B.Fab")
		)
		(fp_line
			(start -0.120396 0.2794)
			(end 0.12065 0.2794)
			(stroke
				(width 0.1)
				(type default)
			)
			(layer "B.Fab")
		)
		(fp_line
			(start 0.12065 0.2794)
			(end 0.12065 0.3048)
			(stroke
				(width 0.1)
				(type default)
			)
			(layer "B.Fab")
		)
		(fp_line
			(start -0.12065 -0.2794)
			(end -0.12065 -0.3048)
			(stroke
				(width 0.1)
				(type default)
			)
			(layer "B.Fab")
		)
		(fp_line
			(start 0.12065 -0.2794)
			(end -0.12065 -0.2794)
			(stroke
				(width 0.1)
				(type default)
			)
			(layer "B.Fab")
		)
		(fp_line
			(start -0.67945 -0.3048)
			(end -0.67945 0.3048)
			(stroke
				(width 0.1)
				(type default)
			)
			(layer "B.Fab")
		)
		(fp_line
			(start -0.12065 -0.3048)
			(end -0.67945 -0.3048)
			(stroke
				(width 0.1)
				(type default)
			)
			(layer "B.Fab")
		)
		(fp_line
			(start 0.12065 -0.305054)
			(end 0.12065 -0.2794)
			(stroke
				(width 0.1)
				(type default)
			)
			(layer "B.Fab")
		)
		(fp_line
			(start 0.67945 -0.305054)
			(end 0.12065 -0.305054)
			(stroke
				(width 0.1)
				(type default)
			)
			(layer "B.Fab")
		)
		(pad "1" smd circle
			(at 0.40005 0 90)
			(size 0 0)
			(layers "B.Cu" "B.Mask" "B.Paste")
			(net "PVDD18_S5_P1")
		)
		(pad "2" smd circle
			(at -0.40005 0 90)
			(size 0 0)
			(layers "B.Cu" "B.Mask" "B.Paste")
			(net "SMB_CPU1_SEC_SCL")
		)
	)
	(footprint ""
		(layer "B.Cu")
		(at 128.171194 -171.930568 90)
		(property "Reference" "PC340"
			(at 5.751576 1.613154 270)
			(unlocked yes)
			(layer "B.SilkS")
			(effects
				(font
					(size 0.7874 0.5842)
					(thickness 0.1524)
				)
				(justify left mirror)
			)
		)
		(property "Value" ""
			(at 0 0 90)
			(layer "B.Fab")
			(effects
				(font
					(size 1.27 1.27)
				)
				(justify mirror)
			)
		)
		(duplicate_pad_numbers_are_jumpers no)
		(fp_line
			(start 4.533392 -2.249932)
			(end -4.533392 -2.249932)
			(stroke
				(width 0.1524)
				(type default)
			)
			(layer "B.SilkS")
		)
		(fp_line
			(start -4.533392 -2.249932)
			(end -4.533392 2.249932)
			(stroke
				(width 0.1524)
				(type default)
			)
			(layer "B.SilkS")
		)
		(fp_line
			(start 4.533392 2.249932)
			(end 4.533392 -2.249932)
			(stroke
				(width 0.1524)
				(type default)
			)
			(layer "B.SilkS")
		)
		(fp_line
			(start -4.533392 2.249932)
			(end 4.533392 2.249932)
			(stroke
				(width 0.1524)
				(type default)
			)
			(layer "B.SilkS")
		)
		(fp_rect
			(start 4.533392 -2.326132)
			(end 5.39242 2.326132)
			(stroke
				(width 0)
				(type default)
			)
			(fill yes)
			(layer "B.SilkS")
		)
		(fp_line
			(start 3.750056 -2.249932)
			(end -3.750056 -2.249932)
			(stroke
				(width 0.1)
				(type default)
			)
			(layer "B.Fab")
		)
		(fp_line
			(start -3.750056 -2.249932)
			(end -3.750056 2.249932)
			(stroke
				(width 0.1)
				(type default)
			)
			(layer "B.Fab")
		)
		(fp_line
			(start 3.750056 2.249932)
			(end 3.750056 -2.249932)
			(stroke
				(width 0.1)
				(type default)
			)
			(layer "B.Fab")
		)
		(fp_line
			(start -3.750056 2.249932)
			(end 3.750056 2.249932)
			(stroke
				(width 0.1)
				(type default)
			)
			(layer "B.Fab")
		)
		(fp_text user "-"
			(at -4.8514 -0.14605 90)
			(unlocked yes)
			(layer "B.SilkS")
			(effects
				(font
					(size 1.905 1.4224)
					(thickness 0.1524)
				)
				(justify left mirror)
			)
		)
		(fp_text user "+"
			(at 6.322314 0.786384 0)
			(unlocked yes)
			(layer "B.SilkS")
			(effects
				(font
					(size 1.905 1.4224)
					(thickness 0.1524)
				)
				(justify left mirror)
			)
		)
		(fp_text user "-"
			(at -4.8514 -0.14605 90)
			(unlocked yes)
			(layer "B.Fab")
			(effects
				(font
					(size 1.905 1.4224)
					(thickness 0.1524)
				)
				(justify left mirror)
			)
		)
		(fp_text user "+"
			(at 6.322314 0.786384 0)
			(unlocked yes)
			(layer "B.Fab")
			(effects
				(font
					(size 1.905 1.4224)
					(thickness 0.1524)
				)
				(justify left mirror)
			)
		)
		(pad "1" smd rect
			(at 3.199892 0 270)
			(size 2.413 2.8194)
			(layers "B.Cu" "B.Mask" "B.Paste")
			(net "PVDDCR_SOC_P1")
		)
		(pad "2" smd rect
			(at -3.199892 0 270)
			(size 2.413 2.8194)
			(layers "B.Cu" "B.Mask" "B.Paste")
			(net "GND")
		)
	)
	(footprint ""
		(layer "B.Cu")
		(at 91.919044 -390.909302 90)
		(property "Reference" "C342"
			(at 0 0 90)
			(layer "B.SilkS")
			(hide yes)
			(effects
				(font
					(size 1.27 1.27)
				)
				(justify mirror)
			)
		)
		(property "Value" ""
			(at 0 0 90)
			(layer "B.Fab")
			(effects
				(font
					(size 1.27 1.27)
				)
				(justify mirror)
			)
		)
		(duplicate_pad_numbers_are_jumpers no)
		(fp_line
			(start 0.299974 -0.150114)
			(end -0.299974 -0.150114)
			(stroke
				(width 0.1)
				(type default)
			)
			(layer "B.Fab")
		)
		(fp_line
			(start -0.299974 -0.150114)
			(end -0.299974 0.150114)
			(stroke
				(width 0.1)
				(type default)
			)
			(layer "B.Fab")
		)
		(fp_line
			(start 0.299974 0.150114)
			(end 0.299974 -0.150114)
			(stroke
				(width 0.1)
				(type default)
			)
			(layer "B.Fab")
		)
		(fp_line
			(start -0.299974 0.150114)
			(end 0.299974 0.150114)
			(stroke
				(width 0.1)
				(type default)
			)
			(layer "B.Fab")
		)
		(pad "1" smd rect
			(at 0.2667 0 270)
			(size 0.3048 0.381)
			(layers "B.Cu" "B.Mask" "B.Paste")
			(net "P0V9_CPU1_RT_2D")
		)
		(pad "2" smd rect
			(at -0.2667 0 270)
			(size 0.3048 0.381)
			(layers "B.Cu" "B.Mask" "B.Paste")
			(net "GND")
		)
	)
	(footprint ""
		(layer "B.Cu")
		(at 145.217134 -322.101972)
		(property "Reference" "R738"
			(at 0 0 0)
			(layer "B.SilkS")
			(hide yes)
			(effects
				(font
					(size 1.27 1.27)
				)
				(justify mirror)
			)
		)
		(property "Value" ""
			(at 0 0 0)
			(layer "B.Fab")
			(effects
				(font
					(size 1.27 1.27)
				)
				(justify mirror)
			)
		)
		(duplicate_pad_numbers_are_jumpers no)
		(fp_line
			(start -0.7874 -0.4064)
			(end -0.7874 0.4064)
			(stroke
				(width 0.1524)
				(type default)
			)
			(layer "B.SilkS")
		)
		(fp_line
			(start -0.7874 0.4064)
			(end 0.7874 0.4064)
			(stroke
				(width 0.1524)
				(type default)
			)
			(layer "B.SilkS")
		)
		(fp_line
			(start 0.7874 -0.4064)
			(end -0.7874 -0.4064)
			(stroke
				(width 0.1524)
				(type default)
			)
			(layer "B.SilkS")
		)
		(fp_line
			(start 0.7874 0.4064)
			(end 0.7874 -0.4064)
			(stroke
				(width 0.1524)
				(type default)
			)
			(layer "B.SilkS")
		)
		(fp_line
			(start -0.67945 -0.3048)
			(end -0.67945 0.3048)
			(stroke
				(width 0.1)
				(type default)
			)
			(layer "B.Fab")
		)
		(fp_line
			(start -0.67945 0.3048)
			(end -0.120396 0.3048)
			(stroke
				(width 0.1)
				(type default)
			)
			(layer "B.Fab")
		)
		(fp_line
			(start -0.12065 -0.3048)
			(end -0.67945 -0.3048)
			(stroke
				(width 0.1)
				(type default)
			)
			(layer "B.Fab")
		)
		(fp_line
			(start -0.12065 -0.2794)
			(end -0.12065 -0.3048)
			(stroke
				(width 0.1)
				(type default)
			)
			(layer "B.Fab")
		)
		(fp_line
			(start -0.120396 0.2794)
			(end 0.12065 0.2794)
			(stroke
				(width 0.1)
				(type default)
			)
			(layer "B.Fab")
		)
		(fp_line
			(start -0.120396 0.3048)
			(end -0.120396 0.2794)
			(stroke
				(width 0.1)
				(type default)
			)
			(layer "B.Fab")
		)
		(fp_line
			(start 0.12065 -0.305054)
			(end 0.12065 -0.2794)
			(stroke
				(width 0.1)
				(type default)
			)
			(layer "B.Fab")
		)
		(fp_line
			(start 0.12065 -0.2794)
			(end -0.12065 -0.2794)
			(stroke
				(width 0.1)
				(type default)
			)
			(layer "B.Fab")
		)
		(fp_line
			(start 0.12065 0.2794)
			(end 0.12065 0.3048)
			(stroke
				(width 0.1)
				(type default)
			)
			(layer "B.Fab")
		)
		(fp_line
			(start 0.12065 0.3048)
			(end 0.67945 0.3048)
			(stroke
				(width 0.1)
				(type default)
			)
			(layer "B.Fab")
		)
		(fp_line
			(start 0.67945 -0.305054)
			(end 0.12065 -0.305054)
			(stroke
				(width 0.1)
				(type default)
			)
			(layer "B.Fab")
		)
		(fp_line
			(start 0.67945 0.3048)
			(end 0.67945 -0.305054)
			(stroke
				(width 0.1)
				(type default)
			)
			(layer "B.Fab")
		)
		(pad "1" smd circle
			(at 0.40005 0 180)
			(size 0 0)
			(layers "B.Cu" "B.Mask" "B.Paste")
			(net "SPI_CPU1_CLK")
		)
		(pad "2" smd circle
			(at -0.40005 0 180)
			(size 0 0)
			(layers "B.Cu" "B.Mask" "B.Paste")
			(net "SPI_CPU1_R_CLK")
		)
	)
	(footprint ""
		(layer "B.Cu")
		(at 233.68 -226.822)
		(property "Reference" "R151"
			(at 0 0 0)
			(layer "B.SilkS")
			(hide yes)
			(effects
				(font
					(size 1.27 1.27)
				)
				(justify mirror)
			)
		)
		(property "Value" ""
			(at 0 0 0)
			(layer "B.Fab")
			(effects
				(font
					(size 1.27 1.27)
				)
				(justify mirror)
			)
		)
		(duplicate_pad_numbers_are_jumpers no)
		(fp_line
			(start -0.7874 -0.4064)
			(end -0.7874 0.4064)
			(stroke
				(width 0.1524)
				(type default)
			)
			(layer "B.SilkS")
		)
		(fp_line
			(start -0.7874 0.4064)
			(end 0.7874 0.4064)
			(stroke
				(width 0.1524)
				(type default)
			)
			(layer "B.SilkS")
		)
		(fp_line
			(start 0.7874 -0.4064)
			(end -0.7874 -0.4064)
			(stroke
				(width 0.1524)
				(type default)
			)
			(layer "B.SilkS")
		)
		(fp_line
			(start 0.7874 0.4064)
			(end 0.7874 -0.4064)
			(stroke
				(width 0.1524)
				(type default)
			)
			(layer "B.SilkS")
		)
		(fp_line
			(start -0.67945 -0.3048)
			(end -0.67945 0.3048)
			(stroke
				(width 0.1)
				(type default)
			)
			(layer "B.Fab")
		)
		(fp_line
			(start -0.67945 0.3048)
			(end -0.120396 0.3048)
			(stroke
				(width 0.1)
				(type default)
			)
			(layer "B.Fab")
		)
		(fp_line
			(start -0.12065 -0.3048)
			(end -0.67945 -0.3048)
			(stroke
				(width 0.1)
				(type default)
			)
			(layer "B.Fab")
		)
		(fp_line
			(start -0.12065 -0.2794)
			(end -0.12065 -0.3048)
			(stroke
				(width 0.1)
				(type default)
			)
			(layer "B.Fab")
		)
		(fp_line
			(start -0.120396 0.2794)
			(end 0.12065 0.2794)
			(stroke
				(width 0.1)
				(type default)
			)
			(layer "B.Fab")
		)
		(fp_line
			(start -0.120396 0.3048)
			(end -0.120396 0.2794)
			(stroke
				(width 0.1)
				(type default)
			)
			(layer "B.Fab")
		)
		(fp_line
			(start 0.12065 -0.305054)
			(end 0.12065 -0.2794)
			(stroke
				(width 0.1)
				(type default)
			)
			(layer "B.Fab")
		)
		(fp_line
			(start 0.12065 -0.2794)
			(end -0.12065 -0.2794)
			(stroke
				(width 0.1)
				(type default)
			)
			(layer "B.Fab")
		)
		(fp_line
			(start 0.12065 0.2794)
			(end 0.12065 0.3048)
			(stroke
				(width 0.1)
				(type default)
			)
			(layer "B.Fab")
		)
		(fp_line
			(start 0.12065 0.3048)
			(end 0.67945 0.3048)
			(stroke
				(width 0.1)
				(type default)
			)
			(layer "B.Fab")
		)
		(fp_line
			(start 0.67945 -0.305054)
			(end 0.12065 -0.305054)
			(stroke
				(width 0.1)
				(type default)
			)
			(layer "B.Fab")
		)
		(fp_line
			(start 0.67945 0.3048)
			(end 0.67945 -0.305054)
			(stroke
				(width 0.1)
				(type default)
			)
			(layer "B.Fab")
		)
		(pad "1" smd rect
			(at 0.40005 0)
			(size 0.4572 0.508)
			(layers "B.Cu" "B.Mask" "B.Paste")
			(net "SMB_CPU0_CPU1_APML_SCL")
		)
		(pad "2" smd rect
			(at -0.40005 0)
			(size 0.4572 0.508)
			(layers "B.Cu" "B.Mask" "B.Paste")
			(net "SMB_CPU0_CPU1_APML_BUF2_SCL")
		)
	)
	(footprint ""
		(layer "B.Cu")
		(at 370.905278 -144.520158)
		(property "Reference" "C299"
			(at 0 0 0)
			(layer "B.SilkS")
			(hide yes)
			(effects
				(font
					(size 1.27 1.27)
				)
				(justify mirror)
			)
		)
		(property "Value" ""
			(at 0 0 0)
			(layer "B.Fab")
			(effects
				(font
					(size 1.27 1.27)
				)
				(justify mirror)
			)
		)
		(duplicate_pad_numbers_are_jumpers no)
		(fp_line
			(start -0.7874 -0.4064)
			(end -0.7874 0.4064)
			(stroke
				(width 0.1524)
				(type default)
			)
			(layer "B.SilkS")
		)
		(fp_line
			(start -0.7874 0.4064)
			(end 0.7874 0.4064)
			(stroke
				(width 0.1524)
				(type default)
			)
			(layer "B.SilkS")
		)
		(fp_line
			(start 0.7874 -0.4064)
			(end -0.7874 -0.4064)
			(stroke
				(width 0.1524)
				(type default)
			)
			(layer "B.SilkS")
		)
		(fp_line
			(start 0.7874 0.4064)
			(end 0.7874 -0.4064)
			(stroke
				(width 0.1524)
				(type default)
			)
			(layer "B.SilkS")
		)
		(fp_line
			(start -0.67945 -0.3048)
			(end -0.67945 0.3048)
			(stroke
				(width 0.1)
				(type default)
			)
			(layer "B.Fab")
		)
		(fp_line
			(start -0.67945 0.3048)
			(end -0.120396 0.3048)
			(stroke
				(width 0.1)
				(type default)
			)
			(layer "B.Fab")
		)
		(fp_line
			(start -0.12065 -0.3048)
			(end -0.67945 -0.3048)
			(stroke
				(width 0.1)
				(type default)
			)
			(layer "B.Fab")
		)
		(fp_line
			(start -0.12065 -0.2794)
			(end -0.12065 -0.3048)
			(stroke
				(width 0.1)
				(type default)
			)
			(layer "B.Fab")
		)
		(fp_line
			(start -0.120396 0.2794)
			(end 0.12065 0.2794)
			(stroke
				(width 0.1)
				(type default)
			)
			(layer "B.Fab")
		)
		(fp_line
			(start -0.120396 0.3048)
			(end -0.120396 0.2794)
			(stroke
				(width 0.1)
				(type default)
			)
			(layer "B.Fab")
		)
		(fp_line
			(start 0.12065 -0.305054)
			(end 0.12065 -0.2794)
			(stroke
				(width 0.1)
				(type default)
			)
			(layer "B.Fab")
		)
		(fp_line
			(start 0.12065 -0.2794)
			(end -0.12065 -0.2794)
			(stroke
				(width 0.1)
				(type default)
			)
			(layer "B.Fab")
		)
		(fp_line
			(start 0.12065 0.2794)
			(end 0.12065 0.3048)
			(stroke
				(width 0.1)
				(type default)
			)
			(layer "B.Fab")
		)
		(fp_line
			(start 0.12065 0.3048)
			(end 0.67945 0.3048)
			(stroke
				(width 0.1)
				(type default)
			)
			(layer "B.Fab")
		)
		(fp_line
			(start 0.67945 -0.305054)
			(end 0.12065 -0.305054)
			(stroke
				(width 0.1)
				(type default)
			)
			(layer "B.Fab")
		)
		(fp_line
			(start 0.67945 0.3048)
			(end 0.67945 -0.305054)
			(stroke
				(width 0.1)
				(type default)
			)
			(layer "B.Fab")
		)
		(pad "1" smd circle
			(at 0.40005 0 180)
			(size 0 0)
			(layers "B.Cu" "B.Mask" "B.Paste")
			(net "SVID_PVDDCR_CPU0_P0_SVD_R")
		)
		(pad "2" smd circle
			(at -0.40005 0 180)
			(size 0 0)
			(layers "B.Cu" "B.Mask" "B.Paste")
			(net "GND")
		)
	)
)
